(kicad_pcb
	(version 20260206)
	(generator "pcbnew")
	(generator_version "10.0")
	(general
		(thickness 1.6)
		(legacy_teardrops no)
	)
	(paper "A4")
	(title_block
		(title "04192023_DAF0TMB3IC0_F0TG_MB_C_brd_V02_OCP.brd")
		(comment 1 "Grand Teton / footprints 2784-2790 of 8354")
	)
	(layers
		(0 "F.Cu" signal "TOP")
		(4 "In1.Cu" signal "GND")
		(6 "In2.Cu" signal "IN1")
		(8 "In3.Cu" signal "GND1")
		(10 "In4.Cu" signal "IN2")
		(12 "In5.Cu" signal "GND2")
		(14 "In6.Cu" signal "IN3")
		(16 "In7.Cu" signal "GND3")
		(18 "In8.Cu" signal "VCC")
		(20 "In9.Cu" signal "VCC1")
		(22 "In10.Cu" signal "GND4")
		(24 "In11.Cu" signal "IN4")
		(26 "In12.Cu" signal "GND5")
		(28 "In13.Cu" signal "IN5")
		(30 "In14.Cu" signal "GND6")
		(32 "In15.Cu" signal "IN6")
		(34 "In16.Cu" signal "GND7")
		(2 "B.Cu" signal "BOTTOM")
		(9 "F.Adhes" user "F.Adhesive")
		(11 "B.Adhes" user "B.Adhesive")
		(13 "F.Paste" user "Package Geometry/Pastemask Top")
		(15 "B.Paste" user "Package Geometry/Pastemask Bottom")
		(5 "F.SilkS" user "Ref Des/Silkscreen Top")
		(7 "B.SilkS" user "Ref Des/Silkscreen Bottom")
		(1 "F.Mask" user "Board Geometry/Soldermask Top")
		(3 "B.Mask" user "Board Geometry/Soldermask Bottom")
		(17 "Dwgs.User" user "User.Drawings")
		(19 "Cmts.User" user "User.Comments")
		(21 "Eco1.User" user "User.Eco1")
		(23 "Eco2.User" user "User.Eco2")
		(25 "Edge.Cuts" user "Board Geometry/Outline")
		(27 "Margin" user)
		(31 "F.CrtYd" user "Package Geometry/Place Bound Top")
		(29 "B.CrtYd" user "Package Geometry/Place Bound Bottom")
		(35 "F.Fab" user "Ref Des/Assembly Top")
		(33 "B.Fab" user "Ref Des/Assembly Bottom")
	)
	(footprint ""
		(layer "F.Cu")
		(at 29.214064 -80.424274 -90)
		(property "Reference" "R6182"
			(at 0 0 270)
			(layer "F.SilkS")
			(hide yes)
			(effects
				(font
					(size 1.27 1.27)
				)
			)
		)
		(property "Value" ""
			(at 0 0 270)
			(layer "F.Fab")
			(effects
				(font
					(size 1.27 1.27)
				)
			)
		)
		(duplicate_pad_numbers_are_jumpers no)
		(fp_line
			(start -0.7874 0.4064)
			(end -0.7874 -0.4064)
			(stroke
				(width 0.1524)
				(type default)
			)
			(layer "F.SilkS")
		)
		(fp_line
			(start 0.7874 0.4064)
			(end -0.7874 0.4064)
			(stroke
				(width 0.1524)
				(type default)
			)
			(layer "F.SilkS")
		)
		(fp_line
			(start -0.7874 -0.4064)
			(end 0.7874 -0.4064)
			(stroke
				(width 0.1524)
				(type default)
			)
			(layer "F.SilkS")
		)
		(fp_line
			(start 0.7874 -0.4064)
			(end 0.7874 0.4064)
			(stroke
				(width 0.1524)
				(type default)
			)
			(layer "F.SilkS")
		)
		(fp_line
			(start -0.67945 0.3048)
			(end -0.67945 -0.305054)
			(stroke
				(width 0.1)
				(type default)
			)
			(layer "F.Fab")
		)
		(fp_line
			(start -0.12065 0.3048)
			(end -0.67945 0.3048)
			(stroke
				(width 0.1)
				(type default)
			)
			(layer "F.Fab")
		)
		(fp_line
			(start 0.120396 0.3048)
			(end 0.120396 0.2794)
			(stroke
				(width 0.1)
				(type default)
			)
			(layer "F.Fab")
		)
		(fp_line
			(start 0.67945 0.3048)
			(end 0.120396 0.3048)
			(stroke
				(width 0.1)
				(type default)
			)
			(layer "F.Fab")
		)
		(fp_line
			(start -0.12065 0.2794)
			(end -0.12065 0.3048)
			(stroke
				(width 0.1)
				(type default)
			)
			(layer "F.Fab")
		)
		(fp_line
			(start 0.120396 0.2794)
			(end -0.12065 0.2794)
			(stroke
				(width 0.1)
				(type default)
			)
			(layer "F.Fab")
		)
		(fp_line
			(start -0.12065 -0.2794)
			(end 0.12065 -0.2794)
			(stroke
				(width 0.1)
				(type default)
			)
			(layer "F.Fab")
		)
		(fp_line
			(start 0.12065 -0.2794)
			(end 0.12065 -0.3048)
			(stroke
				(width 0.1)
				(type default)
			)
			(layer "F.Fab")
		)
		(fp_line
			(start 0.12065 -0.3048)
			(end 0.67945 -0.3048)
			(stroke
				(width 0.1)
				(type default)
			)
			(layer "F.Fab")
		)
		(fp_line
			(start 0.67945 -0.3048)
			(end 0.67945 0.3048)
			(stroke
				(width 0.1)
				(type default)
			)
			(layer "F.Fab")
		)
		(fp_line
			(start -0.67945 -0.305054)
			(end -0.12065 -0.305054)
			(stroke
				(width 0.1)
				(type default)
			)
			(layer "F.Fab")
		)
		(fp_line
			(start -0.12065 -0.305054)
			(end -0.12065 -0.2794)
			(stroke
				(width 0.1)
				(type default)
			)
			(layer "F.Fab")
		)
		(pad "1" smd circle
			(at -0.40005 0 270)
			(size 0 0)
			(layers "F.Cu" "F.Mask" "F.Paste")
			(net "P3V3_AUX")
		)
		(pad "2" smd circle
			(at 0.40005 0 270)
			(size 0 0)
			(layers "F.Cu" "F.Mask" "F.Paste")
			(net "PU_U160_EN_N")
		)
	)
	(footprint ""
		(layer "F.Cu")
		(at 142.893542 -383.7432)
		(property "Reference" "R883"
			(at 0 0 0)
			(layer "F.SilkS")
			(hide yes)
			(effects
				(font
					(size 1.27 1.27)
				)
			)
		)
		(property "Value" ""
			(at 0 0 0)
			(layer "F.Fab")
			(effects
				(font
					(size 1.27 1.27)
				)
			)
		)
		(duplicate_pad_numbers_are_jumpers no)
		(fp_line
			(start -0.32512 -0.175006)
			(end 0.32512 -0.175006)
			(stroke
				(width 0.1)
				(type default)
			)
			(layer "F.Fab")
		)
		(fp_line
			(start -0.32512 0.175006)
			(end -0.32512 -0.175006)
			(stroke
				(width 0.1)
				(type default)
			)
			(layer "F.Fab")
		)
		(fp_line
			(start 0.32512 -0.175006)
			(end 0.32512 0.175006)
			(stroke
				(width 0.1)
				(type default)
			)
			(layer "F.Fab")
		)
		(fp_line
			(start 0.32512 0.175006)
			(end -0.32512 0.175006)
			(stroke
				(width 0.1)
				(type default)
			)
			(layer "F.Fab")
		)
		(pad "1" smd rect
			(at -0.2667 0)
			(size 0.3048 0.381)
			(layers "F.Cu" "F.Mask" "F.Paste")
			(net "TEST2_RT_CPU1_P2")
		)
		(pad "2" smd rect
			(at 0.2667 0 180)
			(size 0.3048 0.381)
			(layers "F.Cu" "F.Mask" "F.Paste")
			(net "GND")
		)
	)
	(footprint ""
		(layer "F.Cu")
		(at 15.067788 -92.687648 90)
		(property "Reference" "R3659"
			(at 0 0 90)
			(layer "F.SilkS")
			(hide yes)
			(effects
				(font
					(size 1.27 1.27)
				)
			)
		)
		(property "Value" ""
			(at 0 0 90)
			(layer "F.Fab")
			(effects
				(font
					(size 1.27 1.27)
				)
			)
		)
		(duplicate_pad_numbers_are_jumpers no)
		(fp_line
			(start 0.7874 -0.4064)
			(end 0.7874 0.4064)
			(stroke
				(width 0.1524)
				(type default)
			)
			(layer "F.SilkS")
		)
		(fp_line
			(start -0.7874 -0.4064)
			(end 0.7874 -0.4064)
			(stroke
				(width 0.1524)
				(type default)
			)
			(layer "F.SilkS")
		)
		(fp_line
			(start 0.7874 0.4064)
			(end -0.7874 0.4064)
			(stroke
				(width 0.1524)
				(type default)
			)
			(layer "F.SilkS")
		)
		(fp_line
			(start -0.7874 0.4064)
			(end -0.7874 -0.4064)
			(stroke
				(width 0.1524)
				(type default)
			)
			(layer "F.SilkS")
		)
		(fp_line
			(start -0.12065 -0.305054)
			(end -0.12065 -0.2794)
			(stroke
				(width 0.1)
				(type default)
			)
			(layer "F.Fab")
		)
		(fp_line
			(start -0.67945 -0.305054)
			(end -0.12065 -0.305054)
			(stroke
				(width 0.1)
				(type default)
			)
			(layer "F.Fab")
		)
		(fp_line
			(start 0.67945 -0.3048)
			(end 0.67945 0.3048)
			(stroke
				(width 0.1)
				(type default)
			)
			(layer "F.Fab")
		)
		(fp_line
			(start 0.12065 -0.3048)
			(end 0.67945 -0.3048)
			(stroke
				(width 0.1)
				(type default)
			)
			(layer "F.Fab")
		)
		(fp_line
			(start 0.12065 -0.2794)
			(end 0.12065 -0.3048)
			(stroke
				(width 0.1)
				(type default)
			)
			(layer "F.Fab")
		)
		(fp_line
			(start -0.12065 -0.2794)
			(end 0.12065 -0.2794)
			(stroke
				(width 0.1)
				(type default)
			)
			(layer "F.Fab")
		)
		(fp_line
			(start 0.120396 0.2794)
			(end -0.12065 0.2794)
			(stroke
				(width 0.1)
				(type default)
			)
			(layer "F.Fab")
		)
		(fp_line
			(start -0.12065 0.2794)
			(end -0.12065 0.3048)
			(stroke
				(width 0.1)
				(type default)
			)
			(layer "F.Fab")
		)
		(fp_line
			(start 0.67945 0.3048)
			(end 0.120396 0.3048)
			(stroke
				(width 0.1)
				(type default)
			)
			(layer "F.Fab")
		)
		(fp_line
			(start 0.120396 0.3048)
			(end 0.120396 0.2794)
			(stroke
				(width 0.1)
				(type default)
			)
			(layer "F.Fab")
		)
		(fp_line
			(start -0.12065 0.3048)
			(end -0.67945 0.3048)
			(stroke
				(width 0.1)
				(type default)
			)
			(layer "F.Fab")
		)
		(fp_line
			(start -0.67945 0.3048)
			(end -0.67945 -0.305054)
			(stroke
				(width 0.1)
				(type default)
			)
			(layer "F.Fab")
		)
		(pad "1" smd circle
			(at -0.40005 0 90)
			(size 0 0)
			(layers "F.Cu" "F.Mask" "F.Paste")
			(net "P3V3_AUX")
		)
		(pad "2" smd circle
			(at 0.40005 0 90)
			(size 0 0)
			(layers "F.Cu" "F.Mask" "F.Paste")
			(net "USB_HUB_OVCUR4")
		)
	)
	(footprint ""
		(layer "F.Cu")
		(at 324.00748 -339.84565 90)
		(property "Reference" "PC83_2"
			(at 0 0 90)
			(layer "F.SilkS")
			(hide yes)
			(effects
				(font
					(size 1.27 1.27)
				)
			)
		)
		(property "Value" ""
			(at 0 0 90)
			(layer "F.Fab")
			(effects
				(font
					(size 1.27 1.27)
				)
			)
		)
		(duplicate_pad_numbers_are_jumpers no)
		(fp_line
			(start 0.7874 -0.4064)
			(end 0.7874 0.4064)
			(stroke
				(width 0.1524)
				(type default)
			)
			(layer "F.SilkS")
		)
		(fp_line
			(start -0.7874 -0.4064)
			(end 0.7874 -0.4064)
			(stroke
				(width 0.1524)
				(type default)
			)
			(layer "F.SilkS")
		)
		(fp_line
			(start 0.7874 0.4064)
			(end -0.7874 0.4064)
			(stroke
				(width 0.1524)
				(type default)
			)
			(layer "F.SilkS")
		)
		(fp_line
			(start -0.7874 0.4064)
			(end -0.7874 -0.4064)
			(stroke
				(width 0.1524)
				(type default)
			)
			(layer "F.SilkS")
		)
		(fp_line
			(start -0.12065 -0.305054)
			(end -0.12065 -0.2794)
			(stroke
				(width 0.1)
				(type default)
			)
			(layer "F.Fab")
		)
		(fp_line
			(start -0.67945 -0.305054)
			(end -0.12065 -0.305054)
			(stroke
				(width 0.1)
				(type default)
			)
			(layer "F.Fab")
		)
		(fp_line
			(start 0.67945 -0.3048)
			(end 0.67945 0.3048)
			(stroke
				(width 0.1)
				(type default)
			)
			(layer "F.Fab")
		)
		(fp_line
			(start 0.12065 -0.3048)
			(end 0.67945 -0.3048)
			(stroke
				(width 0.1)
				(type default)
			)
			(layer "F.Fab")
		)
		(fp_line
			(start 0.12065 -0.2794)
			(end 0.12065 -0.3048)
			(stroke
				(width 0.1)
				(type default)
			)
			(layer "F.Fab")
		)
		(fp_line
			(start -0.12065 -0.2794)
			(end 0.12065 -0.2794)
			(stroke
				(width 0.1)
				(type default)
			)
			(layer "F.Fab")
		)
		(fp_line
			(start 0.120396 0.2794)
			(end -0.12065 0.2794)
			(stroke
				(width 0.1)
				(type default)
			)
			(layer "F.Fab")
		)
		(fp_line
			(start -0.12065 0.2794)
			(end -0.12065 0.3048)
			(stroke
				(width 0.1)
				(type default)
			)
			(layer "F.Fab")
		)
		(fp_line
			(start 0.67945 0.3048)
			(end 0.120396 0.3048)
			(stroke
				(width 0.1)
				(type default)
			)
			(layer "F.Fab")
		)
		(fp_line
			(start 0.120396 0.3048)
			(end 0.120396 0.2794)
			(stroke
				(width 0.1)
				(type default)
			)
			(layer "F.Fab")
		)
		(fp_line
			(start -0.12065 0.3048)
			(end -0.67945 0.3048)
			(stroke
				(width 0.1)
				(type default)
			)
			(layer "F.Fab")
		)
		(fp_line
			(start -0.67945 0.3048)
			(end -0.67945 -0.305054)
			(stroke
				(width 0.1)
				(type default)
			)
			(layer "F.Fab")
		)
		(pad "1" smd circle
			(at -0.40005 0 90)
			(size 0 0)
			(layers "F.Cu" "F.Mask" "F.Paste")
			(net "PVDDCR_CPU1_P0_VCCS")
		)
		(pad "2" smd circle
			(at 0.40005 0 90)
			(size 0 0)
			(layers "F.Cu" "F.Mask" "F.Paste")
			(net "GND")
		)
	)
	(footprint ""
		(layer "F.Cu")
		(at 83.222084 -37.36848 180)
		(property "Reference" "R6058"
			(at 0 0 180)
			(layer "F.SilkS")
			(hide yes)
			(effects
				(font
					(size 1.27 1.27)
				)
			)
		)
		(property "Value" ""
			(at 0 0 180)
			(layer "F.Fab")
			(effects
				(font
					(size 1.27 1.27)
				)
			)
		)
		(duplicate_pad_numbers_are_jumpers no)
		(fp_line
			(start 0.7874 0.4064)
			(end -0.7874 0.4064)
			(stroke
				(width 0.1524)
				(type default)
			)
			(layer "F.SilkS")
		)
		(fp_line
			(start 0.7874 -0.4064)
			(end 0.7874 0.4064)
			(stroke
				(width 0.1524)
				(type default)
			)
			(layer "F.SilkS")
		)
		(fp_line
			(start -0.7874 0.4064)
			(end -0.7874 -0.4064)
			(stroke
				(width 0.1524)
				(type default)
			)
			(layer "F.SilkS")
		)
		(fp_line
			(start -0.7874 -0.4064)
			(end 0.7874 -0.4064)
			(stroke
				(width 0.1524)
				(type default)
			)
			(layer "F.SilkS")
		)
		(fp_line
			(start 0.67945 0.3048)
			(end 0.120396 0.3048)
			(stroke
				(width 0.1)
				(type default)
			)
			(layer "F.Fab")
		)
		(fp_line
			(start 0.67945 -0.3048)
			(end 0.67945 0.3048)
			(stroke
				(width 0.1)
				(type default)
			)
			(layer "F.Fab")
		)
		(fp_line
			(start 0.12065 -0.2794)
			(end 0.12065 -0.3048)
			(stroke
				(width 0.1)
				(type default)
			)
			(layer "F.Fab")
		)
		(fp_line
			(start 0.12065 -0.3048)
			(end 0.67945 -0.3048)
			(stroke
				(width 0.1)
				(type default)
			)
			(layer "F.Fab")
		)
		(fp_line
			(start 0.120396 0.3048)
			(end 0.120396 0.2794)
			(stroke
				(width 0.1)
				(type default)
			)
			(layer "F.Fab")
		)
		(fp_line
			(start 0.120396 0.2794)
			(end -0.12065 0.2794)
			(stroke
				(width 0.1)
				(type default)
			)
			(layer "F.Fab")
		)
		(fp_line
			(start -0.12065 0.3048)
			(end -0.67945 0.3048)
			(stroke
				(width 0.1)
				(type default)
			)
			(layer "F.Fab")
		)
		(fp_line
			(start -0.12065 0.2794)
			(end -0.12065 0.3048)
			(stroke
				(width 0.1)
				(type default)
			)
			(layer "F.Fab")
		)
		(fp_line
			(start -0.12065 -0.2794)
			(end 0.12065 -0.2794)
			(stroke
				(width 0.1)
				(type default)
			)
			(layer "F.Fab")
		)
		(fp_line
			(start -0.12065 -0.305054)
			(end -0.12065 -0.2794)
			(stroke
				(width 0.1)
				(type default)
			)
			(layer "F.Fab")
		)
		(fp_line
			(start -0.67945 0.3048)
			(end -0.67945 -0.305054)
			(stroke
				(width 0.1)
				(type default)
			)
			(layer "F.Fab")
		)
		(fp_line
			(start -0.67945 -0.305054)
			(end -0.12065 -0.305054)
			(stroke
				(width 0.1)
				(type default)
			)
			(layer "F.Fab")
		)
		(pad "1" smd circle
			(at -0.40005 0 180)
			(size 0 0)
			(layers "F.Cu" "F.Mask" "F.Paste")
			(net "RST_PERST_OCP_V3_2_BUF2_N")
		)
		(pad "2" smd circle
			(at 0.40005 0 180)
			(size 0 0)
			(layers "F.Cu" "F.Mask" "F.Paste")
			(net "RST_PERST2_OCP_V3_2_N")
		)
	)
	(footprint ""
		(layer "F.Cu")
		(at 91.770454 -337.694524 90)
		(property "Reference" "PC421"
			(at 0 0 90)
			(layer "F.SilkS")
			(hide yes)
			(effects
				(font
					(size 1.27 1.27)
				)
			)
		)
		(property "Value" ""
			(at 0 0 90)
			(layer "F.Fab")
			(effects
				(font
					(size 1.27 1.27)
				)
			)
		)
		(duplicate_pad_numbers_are_jumpers no)
		(fp_line
			(start 0.7874 -0.4064)
			(end 0.7874 0.4064)
			(stroke
				(width 0.1524)
				(type default)
			)
			(layer "F.SilkS")
		)
		(fp_line
			(start -0.7874 -0.4064)
			(end 0.7874 -0.4064)
			(stroke
				(width 0.1524)
				(type default)
			)
			(layer "F.SilkS")
		)
		(fp_line
			(start 0.7874 0.4064)
			(end 0.379476 0.4064)
			(stroke
				(width 0.1524)
				(type default)
			)
			(layer "F.SilkS")
		)
		(fp_line
			(start -0.230124 0.4064)
			(end -0.7874 0.4064)
			(stroke
				(width 0.1524)
				(type default)
			)
			(layer "F.SilkS")
		)
		(fp_line
			(start -0.7874 0.4064)
			(end -0.7874 -0.4064)
			(stroke
				(width 0.1524)
				(type default)
			)
			(layer "F.SilkS")
		)
		(fp_line
			(start -0.12065 -0.305054)
			(end -0.12065 -0.2794)
			(stroke
				(width 0.1)
				(type default)
			)
			(layer "F.Fab")
		)
		(fp_line
			(start -0.67945 -0.305054)
			(end -0.12065 -0.305054)
			(stroke
				(width 0.1)
				(type default)
			)
			(layer "F.Fab")
		)
		(fp_line
			(start 0.67945 -0.3048)
			(end 0.67945 0.3048)
			(stroke
				(width 0.1)
				(type default)
			)
			(layer "F.Fab")
		)
		(fp_line
			(start 0.12065 -0.3048)
			(end 0.67945 -0.3048)
			(stroke
				(width 0.1)
				(type default)
			)
			(layer "F.Fab")
		)
		(fp_line
			(start 0.12065 -0.2794)
			(end 0.12065 -0.3048)
			(stroke
				(width 0.1)
				(type default)
			)
			(layer "F.Fab")
		)
		(fp_line
			(start -0.12065 -0.2794)
			(end 0.12065 -0.2794)
			(stroke
				(width 0.1)
				(type default)
			)
			(layer "F.Fab")
		)
		(fp_line
			(start 0.120396 0.2794)
			(end -0.12065 0.2794)
			(stroke
				(width 0.1)
				(type default)
			)
			(layer "F.Fab")
		)
		(fp_line
			(start -0.12065 0.2794)
			(end -0.12065 0.3048)
			(stroke
				(width 0.1)
				(type default)
			)
			(layer "F.Fab")
		)
		(fp_line
			(start 0.67945 0.3048)
			(end 0.120396 0.3048)
			(stroke
				(width 0.1)
				(type default)
			)
			(layer "F.Fab")
		)
		(fp_line
			(start 0.120396 0.3048)
			(end 0.120396 0.2794)
			(stroke
				(width 0.1)
				(type default)
			)
			(layer "F.Fab")
		)
		(fp_line
			(start -0.12065 0.3048)
			(end -0.67945 0.3048)
			(stroke
				(width 0.1)
				(type default)
			)
			(layer "F.Fab")
		)
		(fp_line
			(start -0.67945 0.3048)
			(end -0.67945 -0.305054)
			(stroke
				(width 0.1)
				(type default)
			)
			(layer "F.Fab")
		)
		(pad "1" smd circle
			(at -0.40005 0 90)
			(size 0 0)
			(layers "F.Cu" "F.Mask" "F.Paste")
			(net "PVDDCR_CPU1_P1_VCC5")
		)
		(pad "2" smd circle
			(at 0.40005 0 90)
			(size 0 0)
			(layers "F.Cu" "F.Mask" "F.Paste")
			(net "GND")
		)
	)
	(footprint ""
		(layer "F.Cu")
		(at 71.882 -385.5212 90)
		(property "Reference" "R6712"
			(at 0 0 90)
			(layer "F.SilkS")
			(hide yes)
			(effects
				(font
					(size 1.27 1.27)
				)
			)
		)
		(property "Value" ""
			(at 0 0 90)
			(layer "F.Fab")
			(effects
				(font
					(size 1.27 1.27)
				)
			)
		)
		(duplicate_pad_numbers_are_jumpers no)
		(fp_line
			(start 0.32512 -0.175006)
			(end 0.32512 0.175006)
			(stroke
				(width 0.1)
				(type default)
			)
			(layer "F.Fab")
		)
		(fp_line
			(start -0.32512 -0.175006)
			(end 0.32512 -0.175006)
			(stroke
				(width 0.1)
				(type default)
			)
			(layer "F.Fab")
		)
		(fp_line
			(start 0.32512 0.175006)
			(end -0.32512 0.175006)
			(stroke
				(width 0.1)
				(type default)
			)
			(layer "F.Fab")
		)
		(fp_line
			(start -0.32512 0.175006)
			(end -0.32512 -0.175006)
			(stroke
				(width 0.1)
				(type default)
			)
			(layer "F.Fab")
		)
		(pad "1" smd rect
			(at -0.2667 0 90)
			(size 0.3048 0.381)
			(layers "F.Cu" "F.Mask" "F.Paste")
			(net "P1V8_CPU1_RT_1D")
		)
		(pad "2" smd rect
			(at 0.2667 0 270)
			(size 0.3048 0.381)
			(layers "F.Cu" "F.Mask" "F.Paste")
			(net "RT_CPU1_P0_ADDR3")
		)
	)
)
